(kicad_pcb
	(version 20260206)
	(generator "pcbnew")
	(generator_version "10.0")
	(general
		(thickness 1.21888)
		(legacy_teardrops no)
	)
	(paper "A4")
	(title_block
		(title "timecard-v8 — TimeCard-DC-V8_EXP.PcbDoc")
		(comment 1 "Time Appliance Project (Time Card) / footprints 195-200 of 288")
	)
	(layers
		(0 "F.Cu" signal "TOP")
		(4 "In1.Cu" signal "SGND")
		(6 "In2.Cu" signal "IN1")
		(8 "In3.Cu" signal "IN2")
		(10 "In4.Cu" signal "SGND1")
		(2 "B.Cu" signal "BOTTOM")
		(9 "F.Adhes" user "F.Adhesive")
		(11 "B.Adhes" user "B.Adhesive")
		(13 "F.Paste" user "Top Paste")
		(15 "B.Paste" user "Bottom Paste")
		(5 "F.SilkS" user "Top Overlay")
		(7 "B.SilkS" user "Bottom Overlay")
		(1 "F.Mask" user "Top Solder")
		(3 "B.Mask" user "Bottom Solder")
		(17 "Dwgs.User" user "User.Drawings")
		(19 "Cmts.User" user "User.Comments")
		(21 "Eco1.User" user "User.Eco1")
		(23 "Eco2.User" user "User.Eco2")
		(25 "Edge.Cuts" user)
		(27 "Margin" user)
		(31 "F.CrtYd" user "Top Courtyard")
		(29 "B.CrtYd" user "Bottom Courtyard")
		(35 "F.Fab" user "Top Component Center")
		(33 "B.Fab" user "Bottom Component Center")
	)
	(footprint "Vault:RESC3216X89X64NL25T25"
		(layer "F.Cu")
		(at 225.9261 107.4162 90)
		(property "Reference" "R8"
			(at 1.7 1.206655 270)
			(unlocked yes)
			(layer "F.SilkS")
			(effects
				(font
					(size 0.762 0.762)
					(thickness 0.2286)
				)
				(justify left bottom)
			)
		)
		(property "Value" "2mOhm_1%_1206"
			(at -6.763245 16.2553 0)
			(unlocked yes)
			(layer "F.SilkS")
			(hide yes)
			(effects
				(font
					(size 0.762 0.762)
					(thickness 0.2286)
				)
				(justify left bottom)
			)
		)
		(sheetname "POWER")
		(sheetfile "POWER.kicad_sch")
		(duplicate_pad_numbers_are_jumpers no)
		(fp_line
			(start -0.2 -0.825)
			(end 0.2 -0.825)
			(stroke
				(width 0.2)
				(type solid)
			)
			(layer "F.SilkS")
		)
		(fp_line
			(start -0.2 0.825)
			(end 0.2 0.825)
			(stroke
				(width 0.2)
				(type solid)
			)
			(layer "F.SilkS")
		)
		(pad "1" smd rect
			(at -1.325 0 180)
			(size 1.85 1.5)
			(layers "F.Cu" "F.Mask" "F.Paste")
			(net "P5V_SENSE")
		)
		(pad "2" smd rect
			(at 1.325 0 180)
			(size 1.85 1.5)
			(layers "F.Cu" "F.Mask" "F.Paste")
			(net "+5.0V")
		)
	)
	(footprint "Vault:RESC1608X55X30NL15T15"
		(layer "F.Cu")
		(at 71.6261 55.6162 90)
		(property "Reference" "R36"
			(at -5.7714 -0.223079 90)
			(unlocked yes)
			(layer "F.SilkS")
			(effects
				(font
					(size 0.762 0.762)
					(thickness 0.2286)
				)
			)
		)
		(property "Value" "200 OHM"
			(at -2.935471 4.78626 0)
			(unlocked yes)
			(layer "F.SilkS")
			(hide yes)
			(effects
				(font
					(size 0.762 0.762)
					(thickness 0.2286)
				)
			)
		)
		(sheetname "USER_IO_STATUS")
		(sheetfile "USER_IO_STATUS.kicad_sch")
		(duplicate_pad_numbers_are_jumpers no)
		(pad "1" smd rect
			(at -0.675 0 180)
			(size 0.95 0.8)
			(layers "F.Cu" "F.Mask" "F.Paste")
			(net "LED2")
		)
		(pad "2" smd rect
			(at 0.675 0 180)
			(size 0.95 0.8)
			(layers "F.Cu" "F.Mask" "F.Paste")
			(net "NetD9_1")
		)
	)
	(footprint "Vault:FP-0603-L_1_6_0_2-W_0_8_0-MFG"
		(layer "F.Cu")
		(at 226.5261 130.0162 -90)
		(property "Reference" "C85"
			(at -0.2286 1.573079 90)
			(unlocked yes)
			(layer "F.SilkS")
			(effects
				(font
					(size 0.762 0.762)
					(thickness 0.2286)
				)
			)
		)
		(property "Value" "10uF_16V_0603"
			(at -2.871951 8.95046 180)
			(unlocked yes)
			(layer "F.SilkS")
			(hide yes)
			(effects
				(font
					(size 0.762 0.762)
					(thickness 0.2286)
				)
			)
		)
		(sheetname "POWER")
		(sheetfile "POWER.kicad_sch")
		(duplicate_pad_numbers_are_jumpers no)
		(fp_line
			(start 0.9 0.825)
			(end -0.9 0.825)
			(stroke
				(width 0.2)
				(type solid)
			)
			(layer "F.SilkS")
		)
		(fp_line
			(start 0.9 -0.825)
			(end -0.9 -0.825)
			(stroke
				(width 0.2)
				(type solid)
			)
			(layer "F.SilkS")
		)
		(fp_line
			(start -1.15 0.6)
			(end -1.15 -0.6)
			(stroke
				(width 0.2)
				(type solid)
			)
			(layer "F.CrtYd")
		)
		(fp_line
			(start 1.15 0.6)
			(end -1.15 0.6)
			(stroke
				(width 0.2)
				(type solid)
			)
			(layer "F.CrtYd")
		)
		(fp_line
			(start 1.15 0.6)
			(end 1.15 -0.6)
			(stroke
				(width 0.2)
				(type solid)
			)
			(layer "F.CrtYd")
		)
		(fp_line
			(start 1.15 -0.6)
			(end -1.15 -0.6)
			(stroke
				(width 0.2)
				(type solid)
			)
			(layer "F.CrtYd")
		)
		(fp_line
			(start -1.15 0.6)
			(end -1.15 -0.6)
			(stroke
				(width 0.2)
				(type solid)
			)
			(layer "F.Fab")
		)
		(fp_line
			(start 1.15 0.6)
			(end -1.15 0.6)
			(stroke
				(width 0.2)
				(type solid)
			)
			(layer "F.Fab")
		)
		(fp_line
			(start 1.15 0.6)
			(end 1.15 -0.6)
			(stroke
				(width 0.2)
				(type solid)
			)
			(layer "F.Fab")
		)
		(fp_line
			(start 0 0.5)
			(end 0 -0.5)
			(stroke
				(width 0.1)
				(type solid)
			)
			(layer "F.Fab")
		)
		(fp_line
			(start 0.5 0)
			(end -0.5 0)
			(stroke
				(width 0.1)
				(type solid)
			)
			(layer "F.Fab")
		)
		(fp_line
			(start 1.15 -0.6)
			(end -1.15 -0.6)
			(stroke
				(width 0.2)
				(type solid)
			)
			(layer "F.Fab")
		)
		(fp_text user "${REFERENCE}"
			(at -0.00001 0.09602 270)
			(unlocked yes)
			(layer "F.Fab")
			(effects
				(font
					(face "Arial")
					(size 0.63 0.63)
					(thickness 0.1)
				)
				(justify left bottom)
			)
		)
		(pad "1" smd rect
			(at -0.7 0 270)
			(size 0.7 0.7)
			(layers "F.Cu" "F.Mask" "F.Paste")
			(net "+3.3V")
			(solder_mask_margin 0)
			(solder_paste_margin 0)
		)
		(pad "2" smd rect
			(at 0.7 0 270)
			(size 0.7 0.7)
			(layers "F.Cu" "F.Mask" "F.Paste")
			(net "GND")
			(solder_mask_margin 0)
			(solder_paste_margin 0)
		)
	)
	(footprint "Vault:FP-MK212BG-MFG"
		(layer "F.Cu")
		(at 94.3761 74.4286 -90)
		(property "Reference" "C58"
			(at 4.4 -0.843345 90)
			(unlocked yes)
			(layer "F.SilkS")
			(effects
				(font
					(size 0.762 0.762)
					(thickness 0.2286)
				)
				(justify left bottom)
			)
		)
		(property "Value" "10uF"
			(at 5.233445 1.5875 0)
			(unlocked yes)
			(layer "F.SilkS")
			(hide yes)
			(effects
				(font
					(size 0.762 0.762)
					(thickness 0.2286)
				)
				(justify left bottom)
			)
		)
		(sheetname "GPS_IMU_SENSORS")
		(sheetfile "GPS_IMU_SENSORS.kicad_sch")
		(duplicate_pad_numbers_are_jumpers no)
		(fp_line
			(start 0.125 0.725)
			(end -0.125 0.725)
			(stroke
				(width 0.2)
				(type solid)
			)
			(layer "F.SilkS")
		)
		(fp_line
			(start 0.125 -0.725)
			(end -0.125 -0.725)
			(stroke
				(width 0.2)
				(type solid)
			)
			(layer "F.SilkS")
		)
		(fp_line
			(start -1.6 0.825)
			(end -1.6 -0.825)
			(stroke
				(width 0.2)
				(type solid)
			)
			(layer "F.CrtYd")
		)
		(fp_line
			(start 1.6 0.825)
			(end -1.6 0.825)
			(stroke
				(width 0.2)
				(type solid)
			)
			(layer "F.CrtYd")
		)
		(fp_line
			(start 1.6 0.825)
			(end 1.6 -0.825)
			(stroke
				(width 0.2)
				(type solid)
			)
			(layer "F.CrtYd")
		)
		(fp_line
			(start 1.6 -0.825)
			(end -1.6 -0.825)
			(stroke
				(width 0.2)
				(type solid)
			)
			(layer "F.CrtYd")
		)
		(fp_line
			(start -1.6 0.825)
			(end -1.6 -0.825)
			(stroke
				(width 0.2)
				(type solid)
			)
			(layer "F.Fab")
		)
		(fp_line
			(start 1.6 0.825)
			(end -1.6 0.825)
			(stroke
				(width 0.2)
				(type solid)
			)
			(layer "F.Fab")
		)
		(fp_line
			(start 1.6 0.825)
			(end 1.6 -0.825)
			(stroke
				(width 0.2)
				(type solid)
			)
			(layer "F.Fab")
		)
		(fp_line
			(start 0 0.5)
			(end 0 -0.5)
			(stroke
				(width 0.1)
				(type solid)
			)
			(layer "F.Fab")
		)
		(fp_line
			(start 0.5 0)
			(end -0.5 0)
			(stroke
				(width 0.1)
				(type solid)
			)
			(layer "F.Fab")
		)
		(fp_line
			(start 1.6 -0.825)
			(end -1.6 -0.825)
			(stroke
				(width 0.2)
				(type solid)
			)
			(layer "F.Fab")
		)
		(fp_text user "${REFERENCE}"
			(at -0.00001 0.09602 270)
			(unlocked yes)
			(layer "F.Fab")
			(effects
				(font
					(face "Arial")
					(size 0.63 0.63)
					(thickness 0.1)
				)
				(justify left bottom)
			)
		)
		(pad "1" smd rect
			(at -1 0 270)
			(size 1 1.25)
			(layers "F.Cu" "F.Mask" "F.Paste")
			(net "+3.3V")
			(solder_mask_margin 0)
			(solder_paste_margin 0)
		)
		(pad "2" smd rect
			(at 1 0 270)
			(size 1 1.25)
			(layers "F.Cu" "F.Mask" "F.Paste")
			(net "GND")
			(solder_mask_margin 0)
			(solder_paste_margin 0)
		)
	)
	(footprint "Vault:FP-0402-L_1_0_1-W_0_5_0_1-IPC_C"
		(layer "F.Cu")
		(at 239.3261 71.9162)
		(property "Reference" "C89"
			(at -1.8714 0.226921 0)
			(unlocked yes)
			(layer "F.SilkS")
			(effects
				(font
					(size 0.762 0.762)
					(thickness 0.2286)
				)
			)
		)
		(property "Value" "0.1uF_25V_0402"
			(at -2.465551 9.839215 270)
			(unlocked yes)
			(layer "F.SilkS")
			(hide yes)
			(effects
				(font
					(size 0.762 0.762)
					(thickness 0.2286)
				)
			)
		)
		(sheetname "USBUart_DipSelects")
		(sheetfile "USBUart_DipSelects.kicad_sch")
		(duplicate_pad_numbers_are_jumpers no)
		(fp_line
			(start -0.65607 -0.7)
			(end 0.65607 -0.7)
			(stroke
				(width 0.2)
				(type solid)
			)
			(layer "F.SilkS")
		)
		(fp_line
			(start -0.65607 0.7)
			(end 0.65607 0.7)
			(stroke
				(width 0.2)
				(type solid)
			)
			(layer "F.SilkS")
		)
		(fp_line
			(start -0.75607 -0.4)
			(end 0.75607 -0.4)
			(stroke
				(width 0.2)
				(type solid)
			)
			(layer "F.CrtYd")
		)
		(fp_line
			(start -0.75607 0.4)
			(end -0.75607 -0.4)
			(stroke
				(width 0.2)
				(type solid)
			)
			(layer "F.CrtYd")
		)
		(fp_line
			(start -0.75607 0.4)
			(end 0.75607 0.4)
			(stroke
				(width 0.2)
				(type solid)
			)
			(layer "F.CrtYd")
		)
		(fp_line
			(start 0.75607 0.4)
			(end 0.75607 -0.4)
			(stroke
				(width 0.2)
				(type solid)
			)
			(layer "F.CrtYd")
		)
		(fp_line
			(start -0.75607 -0.4)
			(end 0.75607 -0.4)
			(stroke
				(width 0.2)
				(type solid)
			)
			(layer "F.Fab")
		)
		(fp_line
			(start -0.75607 0.4)
			(end -0.75607 -0.4)
			(stroke
				(width 0.2)
				(type solid)
			)
			(layer "F.Fab")
		)
		(fp_line
			(start -0.75607 0.4)
			(end 0.75607 0.4)
			(stroke
				(width 0.2)
				(type solid)
			)
			(layer "F.Fab")
		)
		(fp_line
			(start -0.5 0)
			(end 0.5 0)
			(stroke
				(width 0.1)
				(type solid)
			)
			(layer "F.Fab")
		)
		(fp_line
			(start 0 0.5)
			(end 0 -0.5)
			(stroke
				(width 0.1)
				(type solid)
			)
			(layer "F.Fab")
		)
		(fp_line
			(start 0.75607 0.4)
			(end 0.75607 -0.4)
			(stroke
				(width 0.2)
				(type solid)
			)
			(layer "F.Fab")
		)
		(fp_text user "${REFERENCE}"
			(at -0.00001 0.09602 360)
			(unlocked yes)
			(layer "F.Fab")
			(effects
				(font
					(face "Arial")
					(size 0.63 0.63)
					(thickness 0.1)
				)
				(justify left bottom)
			)
		)
		(pad "1" smd rect
			(at -0.36554 0)
			(size 0.58106 0.51213)
			(layers "F.Cu" "F.Mask" "F.Paste")
			(net "FTDI_VBUS")
			(solder_mask_margin 0)
			(solder_paste_margin 0)
		)
		(pad "2" smd rect
			(at 0.36554 0)
			(size 0.58106 0.51213)
			(layers "F.Cu" "F.Mask" "F.Paste")
			(net "GND")
			(solder_mask_margin 0)
			(solder_paste_margin 0)
		)
	)
	(footprint "Vault:FP-D0008A-MFG"
		(layer "F.Cu")
		(at 233.1261 113.1162 180)
		(property "Reference" "U17"
			(at -2.8714 -3.273069 180)
			(unlocked yes)
			(layer "F.SilkS")
			(effects
				(font
					(size 0.762 0.762)
					(thickness 0.2286)
				)
			)
		)
		(property "Value" "INA219BIDR"
			(at 3.16004 4.408671 180)
			(unlocked yes)
			(layer "F.SilkS")
			(hide yes)
			(effects
				(font
					(size 0.762 0.762)
					(thickness 0.2286)
				)
			)
		)
		(sheetname "POWER")
		(sheetfile "POWER.kicad_sch")
		(duplicate_pad_numbers_are_jumpers no)
		(fp_line
			(start 1.5 2.5)
			(end -1.5 2.5)
			(stroke
				(width 0.2)
				(type solid)
			)
			(layer "F.SilkS")
		)
		(fp_line
			(start 1.5 -2.5)
			(end 1.5 2.5)
			(stroke
				(width 0.2)
				(type solid)
			)
			(layer "F.SilkS")
		)
		(fp_line
			(start 1.5 -2.5)
			(end -1.5 -2.5)
			(stroke
				(width 0.2)
				(type solid)
			)
			(layer "F.SilkS")
		)
		(fp_line
			(start -1.5 -2.5)
			(end -1.5 2.5)
			(stroke
				(width 0.2)
				(type solid)
			)
			(layer "F.SilkS")
		)
		(fp_circle
			(center -0.725 -1.725)
			(end -0.725 -1.475)
			(stroke
				(width 0.5)
				(type solid)
			)
			(fill no)
			(layer "F.SilkS")
		)
		(fp_circle
			(center -4.05 -1.905)
			(end -4.05 -1.78)
			(stroke
				(width 0.25)
				(type solid)
			)
			(fill no)
			(layer "F.SilkS")
		)
		(fp_line
			(start 3.575 2.75)
			(end -3.575 2.75)
			(stroke
				(width 0.2)
				(type solid)
			)
			(layer "F.CrtYd")
		)
		(fp_line
			(start 3.575 -2.75)
			(end 3.575 2.75)
			(stroke
				(width 0.2)
				(type solid)
			)
			(layer "F.CrtYd")
		)
		(fp_line
			(start 3.575 -2.75)
			(end -3.575 -2.75)
			(stroke
				(width 0.2)
				(type solid)
			)
			(layer "F.CrtYd")
		)
		(fp_line
			(start -3.575 -2.75)
			(end -3.575 2.75)
			(stroke
				(width 0.2)
				(type solid)
			)
			(layer "F.CrtYd")
		)
		(fp_line
			(start 3.575 2.75)
			(end -3.575 2.75)
			(stroke
				(width 0.2)
				(type solid)
			)
			(layer "F.Fab")
		)
		(fp_line
			(start 3.575 -2.75)
			(end 3.575 2.75)
			(stroke
				(width 0.2)
				(type solid)
			)
			(layer "F.Fab")
		)
		(fp_line
			(start 3.575 -2.75)
			(end -3.575 -2.75)
			(stroke
				(width 0.2)
				(type solid)
			)
			(layer "F.Fab")
		)
		(fp_line
			(start 0.5 0)
			(end -0.5 0)
			(stroke
				(width 0.1)
				(type solid)
			)
			(layer "F.Fab")
		)
		(fp_line
			(start 0 -0.5)
			(end 0 0.5)
			(stroke
				(width 0.1)
				(type solid)
			)
			(layer "F.Fab")
		)
		(fp_line
			(start -3.575 -2.75)
			(end -3.575 2.75)
			(stroke
				(width 0.2)
				(type solid)
			)
			(layer "F.Fab")
		)
		(fp_text user "${REFERENCE}"
			(at -0.00001 0.09601 180)
			(unlocked yes)
			(layer "F.Fab")
			(effects
				(font
					(face "Arial")
					(size 0.63 0.63)
					(thickness 0.1)
				)
				(justify left bottom)
			)
		)
		(pad "1" smd roundrect
			(at -2.7 -1.905 180)
			(size 1.55 0.6)
			(layers "F.Cu" "F.Mask" "F.Paste")
			(roundrect_rratio 0.085)
			(net "NetR66_1")
			(solder_mask_margin 0)
			(solder_paste_margin 0)
		)
		(pad "2" smd roundrect
			(at -2.7 -0.635 180)
			(size 1.55 0.6)
			(layers "F.Cu" "F.Mask" "F.Paste")
			(roundrect_rratio 0.085)
			(net "NetR65_1")
			(solder_mask_margin 0)
			(solder_paste_margin 0)
		)
		(pad "3" smd roundrect
			(at -2.7 0.635 180)
			(size 1.55 0.6)
			(layers "F.Cu" "F.Mask" "F.Paste")
			(roundrect_rratio 0.085)
			(net "SDA")
			(solder_mask_margin 0)
			(solder_paste_margin 0)
		)
		(pad "4" smd roundrect
			(at -2.7 1.905 180)
			(size 1.55 0.6)
			(layers "F.Cu" "F.Mask" "F.Paste")
			(roundrect_rratio 0.085)
			(net "SCL")
			(solder_mask_margin 0)
			(solder_paste_margin 0)
		)
		(pad "5" smd roundrect
			(at 2.7 1.905 180)
			(size 1.55 0.6)
			(layers "F.Cu" "F.Mask" "F.Paste")
			(roundrect_rratio 0.085)
			(net "+3.3V")
			(solder_mask_margin 0)
			(solder_paste_margin 0)
		)
		(pad "6" smd roundrect
			(at 2.7 0.635 180)
			(size 1.55 0.6)
			(layers "F.Cu" "F.Mask" "F.Paste")
			(roundrect_rratio 0.085)
			(net "GND")
			(solder_mask_margin 0)
			(solder_paste_margin 0)
		)
		(pad "7" smd roundrect
			(at 2.7 -0.635 180)
			(size 1.55 0.6)
			(layers "F.Cu" "F.Mask" "F.Paste")
			(roundrect_rratio 0.085)
			(net "+5.0V")
			(solder_mask_margin 0)
			(solder_paste_margin 0)
		)
		(pad "8" smd roundrect
			(at 2.7 -1.905 180)
			(size 1.55 0.6)
			(layers "F.Cu" "F.Mask" "F.Paste")
			(roundrect_rratio 0.085)
			(net "P5V_SENSE")
			(solder_mask_margin 0)
			(solder_paste_margin 0)
		)
	)
)
